%FSTAX23Y23*%
%MOIN*%
%SFA1B1*%

%IPPOS*%
%ADD9517C,0.039370*%
%LNtimingcard_pcb-slotholes-1*%
%LPD*%
G54D9517*
X05934Y03977D02*
Y03898D01*
X06169Y03819D02*
X0607D01*
X06159Y04056D02*
X0608D01*
M02*